FILE_TYPE = MACRO_DRAWING;
SET COLOR_WIRE YELLOW;
SET COLOR_PROP ORANGE;
SET COLOR_DOT WHITE;
SET COLOR_ARC YELLOW;
SET COLOR_BODY GREEN;
SET COLOR_NOTE PURPLE;
SET PROP_DISPLAY VALUE;
FORCEADD SYNONYM..1
(1850 2050);
PAINT MONO (1850 2050);
FORCEPROP 1 LAST NEEDS_NO_SIZE TRUE
J 0
(1875 2125);
DISPLAY 1.000000 (1875 2125);
PAINT MONO (1875 2125);
DISPLAY INVISIBLE (1875 2125);
FORCEPROP 2 LAST PATH 4P
J 0
(1850 2150);
DISPLAY 1.000000 (1850 2150);
PAINT YELLOW (1850 2150);
FORCEPROP 1 LAST BODY_TYPE PLUMBING
J 0
(1850 2100);
DISPLAY 1.000000 (1850 2100);
PAINT GREEN (1850 2100);
DISPLAY INVISIBLE (1850 2100);
FORCEPROP 2 LAST CDS_LIB dev_standard
J 0
(1850 2050);
DISPLAY 0.975610 (1850 2050);
DISPLAY INVISIBLE (1850 2050);
FORCEADD DRAWING..2
(1275 1750);
PAINT MONO (1275 1750);
FORCEPROP 1 LAST LAST_MODIFIED Wed Mar 13 09:19:45 2002
J 0
(1575 1500);
DISPLAY 1.000000 (1575 1500);
PAINT GREEN (1575 1500);
FORCEPROP 1 LAST TITLE P3V3_AUX
J 0
(1325 1700);
DISPLAY 1.000000 (1325 1700);
PAINT GREEN (1325 1700);
FORCEPROP 1 LAST ABBREV P3V3_AUX
J 0
(1325 1650);
DISPLAY 1.000000 (1325 1650);
PAINT GREEN (1325 1650);
WIRE 16 -1 (1800 2050)(1200 2050);
FORCEPROP 2 LAST SIG_NAME G\I
J 0
(1025 2060);
DISPLAY 1.000000 (1025 2060);
PAINT MONO (1025 2060);
WIRE 0 -1 (1900 2050)(2050 2050);
FORCEPROP 2 LAST SIG_NAME P3V3_AUX \G
J 0
(2075 2085);
DISPLAY 1.000000 (2075 2085);
PAINT MONO (2075 2085);
QUIT
